FILE_TYPE = CONNECTIVITY;
{Allegro Design Entry HDL 16.6-p007 (v16-6-112F) 10/10/2012}
"PAGE_NUMBER" = 73;
0"NC";
1"PVCCMCP_CPU1\g";
2"PVCCMCP_CPU1\g";
3"PVCCMCP_CPU1\g";
4"PVCCIO_CPU1\g";
5"TP_CPU1_KTI2_AMONV";
6"VSENSE_PVCCMCP_CPU1_SKT_VSEN";
7"VSENSE_PVSA_CPU1_SKT_VRTN";
8"VSENSE_PVSA_CPU1_SKT_VSEN";
9"VSENSE_PVCCMCP_CPU1_SKT_VRTN";
10"TP_CPU1_RSVD_43";
11"TP_CPU1_RSVD_61";
12"TP_CPU1_KTI2_DFX_DN";
13"TP_CPU1_RSVD_64";
14"TP_CPU1_RSVD_66";
15"TP_CPU1_RSVD_67";
16"TP_CPU1_RSVD_69";
17"TP_CPU1_RSVD_70";
18"TP_CPU1_RSVD_72";
19"TP_CPU1_RSVD_73";
20"PD_CPU1_MCP01_DMON";
21"VSENSE_PVCCIO_CPU1_SKT_VRTN";
22"VSENSE_PVCCIOMCP_CPU1_SKT_VSEN";
23"VSENSE_PVCCIOMCP_CPU1_SKT_VRTN";
24"VSENSE_PVCCIO_CPU1_SKT_VSEN";
25"TP_CPU1_RSVD_0";
26"TP_CPU1_RSVD_1";
27"TP_CPU1_RSVD_2";
28"TP_CPU1_RSVD_3";
29"TP_CPU1_RSVD_4";
30"TP_CPU1_RSVD_5";
31"TP_CPU1_RSVD_6";
32"TP_CPU1_RSVD_7";
33"TP_CPU1_RSVD_8";
34"TP_CPU1_RSVD_9";
35"TP_CPU1_RSVD_10";
36"TP_CPU1_RSVD_11";
37"TP_CPU1_RSVD_12";
38"TP_CPU1_RSVD_13";
39"TP_CPU1_RSVD_14";
40"TP_CPU1_RSVD_15";
41"TP_CPU1_RSVD_16";
42"TP_CPU1_RSVD_17";
43"TP_CPU1_RSVD_18";
44"TP_CPU1_RSVD_19";
45"TP_CPU1_RSVD_20";
46"TP_CPU1_RSVD_21";
47"TP_CPU1_RSVD_22";
48"TP_CPU1_RSVD_23";
49"TP_CPU1_RSVD_24";
50"TP_CPU1_RSVD_25";
51"TP_CPU1_RSVD_26";
52"TP_CPU1_RSVD_27";
53"TP_CPU1_RSVD_28";
54"TP_CPU1_RSVD_29";
55"TP_CPU1_RSVD_30";
56"TP_CPU1_RSVD_31";
57"TP_CPU1_RSVD_32";
58"TP_CPU1_RSVD_33";
59"TP_CPU1_RSVD_34";
60"TP_CPU1_RSVD_35";
61"TP_CPU1_RSVD_36";
62"TP_CPU1_RSVD_37";
63"TP_CPU1_RSVD_38";
64"TP_CPU1_RSVD_39";
65"TP_CPU1_RSVD_40";
66"TP_CPU1_RSVD_41";
67"TP_CPU1_RSVD_42";
68"TP_CPU1_RSVD_44";
69"TP_CPU1_RSVD_45";
70"TP_CPU1_RSVD_46";
71"TP_CPU1_RSVD_47";
72"TP_CPU1_RSVD_48";
73"TP_CPU1_RSVD_49";
74"TP_CPU1_RSVD_50";
75"TP_CPU1_RSVD_51";
76"TP_CPU1_RSVD_53";
77"TP_CPU1_RSVD_54";
78"TP_CPU1_RSVD_55";
79"TP_CPU1_RSVD_56";
80"TP_CPU1_RSVD_57";
81"TP_CPU1_RSVD_59";
82"TP_CPU1_RSVD_60";
%"VCC_CORE"
"1","(-1800,4100)","0","mstr_symbols","I104";
;
HDL_POWER"PVCCMCP_CPU1"
CDS_LIB"mstr_symbols";
"A"1;
%"VCC_CORE"
"1","(-6600,1975)","0","mstr_symbols","I105";
;
HDL_POWER"PVCCMCP_CPU1"
CDS_LIB"mstr_symbols";
"A"2;
%"SKX_EXT_B"
"22","(-4000,2550)","0","chpset_lib","I107";
;
CDS_SEC"22"
MATERIAL"IC"
PART_NUMBER"TBD"
LOCATION"U2D1"
CDS_LOCATION"U2D1"
SEC"22"
CDS_LIB"chpset_lib"
SEC_TYPE"BGA1"
PACK_TYPE"BGA1";
"VSS_VCCSA_SENSE"
$PN"CG76"7;
"VSS_VCCIO_SENSE"
$PN"BF5"21;
"VCCSA_SENSE"
$PN"CE76"8;
"VCCIO_SENSE"
$PN"BH5"24;
"VCCIO<0>"
$PN"EE10"4;
"VCCIO<1>"
$PN"AE10"4;
"VCCIO<2>"
$PN"AF5"4;
"VCCIO<3>"
$PN"DV11"4;
"VCCIO<4>"
$PN"AM5"4;
"VCCIO<5>"
$PN"AT5"4;
"VCCIO<6>"
$PN"AT7"4;
"VCCIO<7>"
$PN"BE24"4;
"VCCIO<8>"
$PN"DK21"4;
"VCCIO<9>"
$PN"CF5"4;
"VCCIO<10>"
$PN"CG14"4;
"VCCIO<11>"
$PN"CL20"4;
"VCCIO<12>"
$PN"CP13"4;
"VCCIO<13>"
$PN"DE14"4;
"VCCIO<14>"
$PN"DC18"4;
"VCCIO<15>"
$PN"CY17"4;
"VCCIO<16>"
$PN"CU18"4;
"VCCIO<17>"
$PN"CV21"4;
"VCCIO<18>"
$PN"CU12"4;
"VCCIO<19>"
$PN"CN6"4;
"RSVD<0>"
$PN"EF83"25;
"RSVD<1>"
$PN"EF81"26;
"RSVD<2>"
$PN"EF77"27;
"RSVD<3>"
$PN"EF47"28;
"RSVD<4>"
$PN"EE84"29;
"RSVD<5>"
$PN"EE82"30;
"RSVD<6>"
$PN"EE6"31;
"RSVD<7>"
$PN"EE46"32;
"RSVD<8>"
$PN"EE16"33;
"RSVD<9>"
$PN"ED83"34;
"RSVD<10>"
$PN"ED5"35;
"RSVD<11>"
$PN"ED45"36;
"RSVD<12>"
$PN"EC84"37;
"RSVD<13>"
$PN"EC44"38;
"RSVD<14>"
$PN"EC4"39;
"RSVD<15>"
$PN"EC16"40;
"RSVD<16>"
$PN"EB85"41;
"RSVD<17>"
$PN"EB5"42;
"RSVD<18>"
$PN"EB3"43;
"RSVD<19>"
$PN"EA44"44;
"RSVD<20>"
$PN"EA4"45;
"RSVD<21>"
$PN"DY3"46;
"RSVD<22>"
$PN"DW46"47;
"RSVD<23>"
$PN"DW44"48;
"RSVD<24>"
$PN"DV71"49;
"RSVD<25>"
$PN"DV61"50;
"RSVD<26>"
$PN"DU44"51;
"RSVD<27>"
$PN"DT71"52;
"RSVD<28>"
$PN"DR44"53;
"RSVD<29>"
$PN"DP65"54;
"RSVD<30>"
$PN"DP17"55;
"RSVD<31>"
$PN"DN66"56;
"RSVD<32>"
$PN"DN62"57;
"RSVD<33>"
$PN"DM67"58;
"RSVD<34>"
$PN"DL66"59;
"RSVD<35>"
$PN"DL38"60;
"RSVD<36>"
$PN"DK67"61;
"RSVD<37>"
$PN"DK65"62;
"RSVD<38>"
$PN"DK37"63;
"RSVD<39>"
$PN"DK15"64;
"RSVD<40>"
$PN"DJ66"65;
"RSVD<41>"
$PN"DJ36"66;
"RSVD<42>"
$PN"DH65"67;
"RSVD<43>"
$PN"DG64"10;
"RSVD<44>"
$PN"DG36"68;
"RSVD<45>"
$PN"DD51"69;
"RSVD<46>"
$PN"DC52"70;
"RSVD<47>"
$PN"DC46"71;
"RSVD<48>"
$PN"DA56"72;
"RSVD<49>"
$PN"DA54"73;
"RSVD<50>"
$PN"DA52"74;
"RSVD<51>"
$PN"DA40"75;
"RSVD<52>"
$PN"DA24"1;
"RSVD<53>"
$PN"CY73"76;
"RSVD<54>"
$PN"CY63"77;
"RSVD<55>"
$PN"CY57"78;
"RSVD<56>"
$PN"CY53"79;
"RSVD<57>"
$PN"CY39"80;
"RSVD<58>"
$PN"CY25"1;
"RSVD<59>"
$PN"CY23"81;
"RSVD<60>"
$PN"CW62"82;
"RSVD<61>"
$PN"CW60"11;
"RSVD<62>"
$PN"CW24"2;
"RSVD<63>"
$PN"CW22"12;
"RSVD<64>"
$PN"CV69"13;
"RSVD<65>"
$PN"CV23"2;
"RSVD<66>"
$PN"CU60"14;
"RSVD<67>"
$PN"CU6"15;
"RSVD<68>"
$PN"CU24"2;
"RSVD<69>"
$PN"CT69"16;
"RSVD<70>"
$PN"CT5"17;
"RSVD<71>"
$PN"CT23"2;
"RSVD<72>"
$PN"CR60"18;
"RSVD<73>"
$PN"CP31"19;
"RSVD<74>"
$PN"CP23"2;
"RSVD<75>"
$PN"CN28"20;
"RSVD<76>"
$PN"CN24"3;
"RSVD<77>"
$PN"CN22"5;
"RSVD<78>"
$PN"CM25"3;
"RSVD<79>"
$PN"CM23"3;
"RSVD<80>"
$PN"CL26"3;
"CD_VSS_VCC_CORE_SENSE"
$PN"BL16"9;
"CD_VCC_CORE_SENSE"
$PN"BN16"6;
"CD_VCCP_SENSE<0>"
$PN"BU16"23;
"CD_VCCP_SENSE<1>"
$PN"BT17"22;
%"VCC_CORE"
"1","(-5925,2950)","0","mstr_symbols","I108";
;
HDL_POWER"PVCCMCP_CPU1"
CDS_LIB"mstr_symbols";
"A"3;
%"PVCCIO_CPU1"
"1","(-5350,4425)","0","mstr_symbols","I22";
;
HDL_POWER"PVCCIO_CPU1"
BODY_TYPE"PLUMBING"
CDS_LIB"mstr_symbols"
VOLTAGE"1.1V";
"G\NAC"4;
END.
